# BASEBOARD_FAB2 (Tioga Pass) — schematic netlist excerpt (pin names and nets, part order shuffled) for the footprints in the layout excerpt that follows; sources: Cadence DE-HDL packaged netlist, KiCad conversion of Wiwynn_Tioga_Pass_MB.brd

C1D11  CAP_A  0.1UF 16V 10% X7R  pkg 0402V  page 199 : A = FM_P12V_HOTSWAP0_EN ; B = AGND_HSC
C8G7  CAP  0.22UF 16V 10% X7R  pkg 0402  page 105 : A = P3E_CPU0_PE2_SS_TXN<1> ; B = P3E_CPU0_PE2_SS_C_TXN<1>

(kicad_pcb
	(version 20260206)
	(generator "pcbnew")
	(generator_version "10.0")
	(general
		(thickness 1.6)
		(legacy_teardrops no)
	)
	(paper "A4")
	(title_block
		(title "Wiwynn_Tioga_Pass_MB.brd")
		(comment 1 "Tioga Pass / footprints 2210-2212 of 4770")
	)
	(layers
		(0 "F.Cu" signal "TOP")
		(4 "In1.Cu" signal "L2GND")
		(6 "In2.Cu" signal "L3")
		(8 "In3.Cu" signal "L4GND")
		(10 "In4.Cu" signal "L5")
		(12 "In5.Cu" signal "L6GND")
		(14 "In6.Cu" signal "L7VCC")
		(16 "In7.Cu" signal "L8VCC")
		(18 "In8.Cu" signal "L9GND")
		(20 "In9.Cu" signal "L10")
		(22 "In10.Cu" signal "L11GND")
		(24 "In11.Cu" signal "L12")
		(26 "In12.Cu" signal "L13GND")
		(2 "B.Cu" signal "BOTTOM")
		(9 "F.Adhes" user "F.Adhesive")
		(11 "B.Adhes" user "B.Adhesive")
		(13 "F.Paste" user "Package Geometry/Pastemask Top")
		(15 "B.Paste" user "Package Geometry/Pastemask Bottom")
		(5 "F.SilkS" user "Ref Des/Silkscreen Top")
		(7 "B.SilkS" user "Ref Des/Silkscreen Bottom")
		(1 "F.Mask" user "Board Geometry/Soldermask Top")
		(3 "B.Mask" user "Board Geometry/Soldermask Bottom")
		(17 "Dwgs.User" user "User.Drawings")
		(19 "Cmts.User" user "User.Comments")
		(21 "Eco1.User" user "User.Eco1")
		(23 "Eco2.User" user "User.Eco2")
		(25 "Edge.Cuts" user "Board Geometry/Outline")
		(27 "Margin" user)
		(31 "F.CrtYd" user "Package Geometry/Place Bound Top")
		(29 "B.CrtYd" user "Package Geometry/Place Bound Bottom")
		(35 "F.Fab" user "Ref Des/Assembly Top")
		(33 "B.Fab" user "Ref Des/Assembly Bottom")
	)
	(footprint ""
		(layer "F.Cu")
		(at 18.923 -79.629 180)
		(property "Reference" "C1D11"
			(at 0 0 180)
			(layer "F.SilkS")
			(hide yes)
			(effects
				(font
					(size 1.27 1.27)
				)
			)
		)
		(property "Value" ""
			(at 0 0 180)
			(layer "F.Fab")
			(effects
				(font
					(size 1.27 1.27)
				)
			)
		)
		(duplicate_pad_numbers_are_jumpers no)
		(fp_rect
			(start -0.3048 -0.1016)
			(end 0.3048 0.9906)
			(stroke
				(width 0)
				(type default)
			)
			(fill no)
			(layer "F.CrtYd")
		)
		(fp_line
			(start 0.3048 0.9906)
			(end 0.3048 -0.1016)
			(stroke
				(width 0.1)
				(type default)
			)
			(layer "F.Fab")
		)
		(fp_line
			(start 0.3048 -0.1016)
			(end -0.3048 -0.1016)
			(stroke
				(width 0.1)
				(type default)
			)
			(layer "F.Fab")
		)
		(fp_line
			(start -0.3048 0.9906)
			(end 0.3048 0.9906)
			(stroke
				(width 0.1)
				(type default)
			)
			(layer "F.Fab")
		)
		(fp_line
			(start -0.3048 -0.1016)
			(end -0.3048 0.9906)
			(stroke
				(width 0.1)
				(type default)
			)
			(layer "F.Fab")
		)
		(pad "1" smd rect
			(at 0 0 180)
			(size 0.508 0.508)
			(layers "F.Cu" "F.Mask" "F.Paste")
			(net "FM_P12V_HOTSWAP0_EN")
		)
		(pad "2" smd rect
			(at 0 0.889 180)
			(size 0.508 0.508)
			(layers "F.Cu" "F.Mask" "F.Paste")
			(net "AGND_HSC")
		)
		(zone
			(layer "F.Cu")
			(hatch none 0.5)
			(connect_pads
				(clearance 0)
			)
			(min_thickness 0.25)
			(keepout
				(tracks allowed)
				(vias not_allowed)
				(pads allowed)
				(copperpour not_allowed)
				(footprints allowed)
			)
			(placement
				(enabled no)
				(sheetname "")
			)
			(fill
				(thermal_gap 0.5)
				(thermal_bridge_width 0.5)
				(island_removal_mode 0)
			)
			(polygon
				(pts
					(xy 19.177 -79.883) (xy 19.177 -80.264) (xy 18.669 -80.264) (xy 18.669 -79.883)
				)
			)
		)
		(zone
			(layer "F.Cu")
			(hatch none 0.5)
			(connect_pads
				(clearance 0)
			)
			(min_thickness 0.25)
			(keepout
				(tracks not_allowed)
				(vias allowed)
				(pads allowed)
				(copperpour not_allowed)
				(footprints allowed)
			)
			(placement
				(enabled no)
				(sheetname "")
			)
			(fill
				(thermal_gap 0.5)
				(thermal_bridge_width 0.5)
				(island_removal_mode 0)
			)
			(polygon
				(pts
					(xy 19.177 -79.883) (xy 19.177 -80.264) (xy 18.669 -80.264) (xy 18.669 -79.883)
				)
			)
		)
	)
	(footprint ""
		(layer "F.Cu")
		(at 210.058 -45.974)
		(property "Reference" ""
			(at 0 0 0)
			(layer "F.SilkS")
			(hide yes)
			(effects
				(font
					(size 1.27 1.27)
				)
			)
		)
		(property "Value" ""
			(at 0 0 0)
			(layer "F.Fab")
			(effects
				(font
					(size 1.27 1.27)
				)
			)
		)
		(duplicate_pad_numbers_are_jumpers no)
		(fp_poly
			(pts
				(arc
					(start 2.032 0)
					(mid -2.032 0)
					(end 2.032 0)
				)
			)
			(stroke
				(width 0)
				(type default)
			)
			(fill no)
			(layer "F.CrtYd")
		)
		(pad "1" smd circle
			(at 0 0)
			(size 1.016 1.016)
			(layers "F.Cu" "F.Mask" "F.Paste")
			(net "Net_395")
		)
		(zone
			(layer "F.Cu")
			(hatch none 0.5)
			(connect_pads
				(clearance 0)
			)
			(min_thickness 0.25)
			(keepout
				(tracks not_allowed)
				(vias allowed)
				(pads allowed)
				(copperpour not_allowed)
				(footprints allowed)
			)
			(placement
				(enabled no)
				(sheetname "")
			)
			(fill
				(thermal_gap 0.5)
				(thermal_bridge_width 0.5)
				(island_removal_mode 0)
			)
			(polygon
				(pts
					(arc
						(start 211.582 -45.974)
						(mid 208.534 -45.974)
						(end 211.582 -45.974)
					)
				)
			)
		)
		(zone
			(layers "F.Cu" "B.Cu" "In1.Cu" "In2.Cu" "In3.Cu" "In4.Cu" "In5.Cu" "In6.Cu"
				"In7.Cu" "In8.Cu" "In9.Cu" "In10.Cu" "In11.Cu" "In12.Cu"
			)
			(hatch none 0.5)
			(connect_pads
				(clearance 0)
			)
			(min_thickness 0.25)
			(keepout
				(tracks allowed)
				(vias not_allowed)
				(pads allowed)
				(copperpour not_allowed)
				(footprints allowed)
			)
			(placement
				(enabled no)
				(sheetname "")
			)
			(fill
				(thermal_gap 0.5)
				(thermal_bridge_width 0.5)
				(island_removal_mode 0)
			)
			(polygon
				(pts
					(arc
						(start 211.582 -45.974)
						(mid 208.534 -45.974)
						(end 211.582 -45.974)
					)
				)
			)
		)
	)
	(footprint ""
		(layer "F.Cu")
		(at 407.631392 -10.916666)
		(property "Reference" "C8G7"
			(at 0 0 0)
			(layer "F.SilkS")
			(hide yes)
			(effects
				(font
					(size 1.27 1.27)
				)
			)
		)
		(property "Value" ""
			(at 0 0 0)
			(layer "F.Fab")
			(effects
				(font
					(size 1.27 1.27)
				)
			)
		)
		(duplicate_pad_numbers_are_jumpers no)
		(fp_rect
			(start -0.3048 0.9906)
			(end 0.3048 -0.1016)
			(stroke
				(width 0)
				(type default)
			)
			(fill no)
			(layer "F.CrtYd")
		)
		(fp_line
			(start -0.3048 -0.1016)
			(end -0.3048 0.9906)
			(stroke
				(width 0.1)
				(type default)
			)
			(layer "F.Fab")
		)
		(fp_line
			(start -0.3048 0.9906)
			(end 0.3048 0.9906)
			(stroke
				(width 0.1)
				(type default)
			)
			(layer "F.Fab")
		)
		(fp_line
			(start 0.3048 -0.1016)
			(end -0.3048 -0.1016)
			(stroke
				(width 0.1)
				(type default)
			)
			(layer "F.Fab")
		)
		(fp_line
			(start 0.3048 0.9906)
			(end 0.3048 -0.1016)
			(stroke
				(width 0.1)
				(type default)
			)
			(layer "F.Fab")
		)
		(pad "1" smd rect
			(at 0 0)
			(size 0.508 0.508)
			(layers "F.Cu" "F.Mask" "F.Paste")
			(net "P3E_CPU0_PE2_SS_TXN<1>")
		)
		(pad "2" smd rect
			(at 0 0.889)
			(size 0.508 0.508)
			(layers "F.Cu" "F.Mask" "F.Paste")
			(net "P3E_CPU0_PE2_SS_C_TXN<1>")
		)
		(zone
			(layer "F.Cu")
			(hatch none 0.5)
			(connect_pads
				(clearance 0)
			)
			(min_thickness 0.25)
			(keepout
				(tracks allowed)
				(vias not_allowed)
				(pads allowed)
				(copperpour not_allowed)
				(footprints allowed)
			)
			(placement
				(enabled no)
				(sheetname "")
			)
			(fill
				(thermal_gap 0.5)
				(thermal_bridge_width 0.5)
				(island_removal_mode 0)
			)
			(polygon
				(pts
					(xy 407.377392 -10.281666) (xy 407.885392 -10.281666) (xy 407.885392 -10.662666) (xy 407.377392 -10.662666)
				)
			)
		)
	)
)
